FILE_TYPE = CONNECTIVITY;
{Allegro Design Entry HDL 17.2-2016 S081 (4005846) 1/11/2022}
"PAGE_NUMBER" = 50;
0"NC";
1"NC_CPU1_UPI3_APROBE<0>";
2"NC_CPU1_UPI3_APROBE<1>";
3"NC_CPU1_DMI_APROBE<0>";
4"NC_CPU1_DMI_APROBE<1>";
5"TP_TRC_CPU1_PTI<15>";
6"TP_TRC_CPU1_PTI<14>";
7"TP_TRC_CPU1_PTI<13>";
8"TP_TRC_CPU1_PTI<12>";
9"TP_TRC_CPU1_PTI<11>";
10"TP_TRC_CPU1_PTI<10>";
11"TP_TRC_CPU1_PTI<9>";
12"TP_TRC_CPU1_PTI<8>";
13"TP_TRC_CPU1_PTI<7>";
14"TP_TRC_CPU1_PTI<6>";
15"TP_TRC_CPU1_PTI<5>";
16"TP_TRC_CPU1_PTI<4>";
17"TP_TRC_CPU1_PTI<3>";
18"TP_TRC_CPU1_PTI<2>";
19"TP_TRC_CPU1_PTI<1>";
20"TP_TRC_CPU1_PTI<0>";
21"TP_TRC_CPU1_PTI0_CLK";
22"TP_TRC_CPU1_PTI1_CLK";
23"TP_TRC_CPU1_PTI<31>";
24"TP_TRC_CPU1_PTI<30>";
25"TP_TRC_CPU1_PTI<29>";
26"TP_TRC_CPU1_PTI<28>";
27"TP_TRC_CPU1_PTI<27>";
28"TP_TRC_CPU1_PTI<26>";
29"TP_TRC_CPU1_PTI<25>";
30"TP_TRC_CPU1_PTI<24>";
31"TP_TRC_CPU1_PTI<23>";
32"TP_TRC_CPU1_PTI<22>";
33"TP_TRC_CPU1_PTI<21>";
34"TP_TRC_CPU1_PTI<20>";
35"TP_TRC_CPU1_PTI<19>";
36"TP_TRC_CPU1_PTI<18>";
37"TP_TRC_CPU1_PTI<17>";
38"TP_TRC_CPU1_PTI<16>";
39"TP_TRC_CPU1_PTI2_CLK";
40"TP_TRC_CPU1_PTI3_CLK";
41"NC_CPU1_PE3_APROBE<0>";
42"NC_CPU1_PE3_APROBE<1>";
43"NC_CPU1_PE4_APROBE<1>";
44"NC_CPU1_UPI2_APROBE<0>";
45"NC_CPU1_UPI0_APROBE<0>";
46"NC_CPU1_PE4_APROBE<0>";
47"NC_CPU1_UPI0_APROBE<1>";
48"NC_CPU1_UPI2_APROBE<1>";
49"NC_CPU1_PE0_APROBE<1>";
50"NC_CPU1_PE0_APROBE<0>";
51"NC_CPU1_UPI1_APROBE<0>";
52"NC_CPU1_PE2_APROBE<1>";
53"NC_CPU1_UPI1_APROBE<1>";
54"NC_CPU1_PE1_APROBE<1>";
55"NC_CPU1_PE2_APROBE<0>";
56"NC_CPU1_PE1_APROBE<0>";
57"PU_CPU1_UPI0_AC_COUPLING";
58"PU_CPU1_UPI1_AC_COUPLING";
59"PU_CPU1_UPI2_AC_COUPLING";
60"PU_CPU1_UPI3_AC_COUPLING";
%"SOCKET4677_AZIF0045P001C01CS"
"7","(1900,2175)","0","pure_quanta","I23";
;
PART_NUMBER"DGA^7000023"
PART_TYPE"SMLF"
MATERIAL"IO"
VALUE"SOCKET4677_AZIF0045-P001C01CS"
$LOCATION"U1"
CDS_LIB"pure_quanta"
NEEDS_NO_SIZE"TRUE"
CDS_LMAN_SYM_OUTLINE"-1050,1250,1050,-1200"
CDS_LOCATION"U1"
$SEC"7"
CDS_SEC"7";
"UPI3_AC_COUPLING"
$PN"CK71"60;
"UPI2_AC_COUPLING"
$PN"BB65"59;
"UPI1_AC_COUPLING"
$PN"CW19"58;
"UPI0_AC_COUPLING"
$PN"BA23"57;
"RSVD89"
$PN"CE21"56;
"RSVD80"
$PN"CC23"55;
"RSVD79"
$PN"CC21"54;
"RSVD78"
$PN"CA23"53;
"RSVD77"
$PN"CA21"3;
"RSVD75"
$PN"BW23"52;
"RSVD74"
$PN"BW21"4;
"RSVD73"
$PN"BV22"51;
"RSVD66"
$PN"BN21"50;
"RSVD62"
$PN"BL21"49;
"RSVD5"
$PN"AT67"48;
"RSVD3"
$PN"AR17"47;
"RSVD22"
$PN"AV67"46;
"RSVD2"
$PN"AN17"45;
"RSVD14"
$PN"AU68"44;
"RSVD13"
$PN"AU66"43;
"RSVD135"
$PN"CR68"2;
"RSVD130"
$PN"CP69"1;
"RSVD122"
$PN"CM69"42;
"RSVD118"
$PN"CL68"41;
"PTI_DIE01_STB_1"
$PN"BK67"40;
"PTI_DIE01_STB_0"
$PN"BF67"39;
"PTI_DIE010"
$PN"BC70"38;
"PTI_DIE011"
$PN"BE70"37;
"PTI_DIE012"
$PN"BD69"36;
"PTI_DIE013"
$PN"BF69"35;
"PTI_DIE014"
$PN"BH69"34;
"PTI_DIE015"
$PN"BC68"33;
"PTI_DIE016"
$PN"BG68"32;
"PTI_DIE017"
$PN"BD67"31;
"PTI_DIE018"
$PN"BK69"30;
"PTI_DIE019"
$PN"BM69"29;
"PTI_DIE0110"
$PN"BN68"28;
"PTI_DIE0111"
$PN"BG66"27;
"PTI_DIE0112"
$PN"BJ66"26;
"PTI_DIE0113"
$PN"BL66"25;
"PTI_DIE0114"
$PN"BM67"24;
"PTI_DIE0115"
$PN"BN66"23;
"PTI_DIE00_STB_1"
$PN"BY28"22;
"PTI_DIE00_STB_0"
$PN"CB30"21;
"PTI_DIE000"
$PN"CC29"20;
"PTI_DIE001"
$PN"CD28"19;
"PTI_DIE002"
$PN"CC27"18;
"PTI_DIE003"
$PN"BY30"17;
"PTI_DIE004"
$PN"CA29"16;
"PTI_DIE005"
$PN"BV30"15;
"PTI_DIE006"
$PN"CA27"14;
"PTI_DIE007"
$PN"BV28"13;
"PTI_DIE008"
$PN"BU27"12;
"PTI_DIE009"
$PN"BT28"11;
"PTI_DIE0010"
$PN"BU29"10;
"PTI_DIE0011"
$PN"BT30"9;
"PTI_DIE0012"
$PN"BN27"8;
"PTI_DIE0013"
$PN"BP28"7;
"PTI_DIE0014"
$PN"BN29"6;
"PTI_DIE0015"
$PN"BP30"5;
END.
